(kicad_pcb
	(version 20260206)
	(generator "pcbnew")
	(generator_version "10.0")
	(general
		(thickness 1.6)
		(legacy_teardrops no)
	)
	(paper "A4")
	(title_block
		(title "baseboard — 13948-1b.1110WZS1818.brd")
		(comment 1 "Honey Badger (Wiwynn) / footprints 1593-1600 of 2523")
	)
	(layers
		(0 "F.Cu" signal "TOP")
		(4 "In1.Cu" signal "L2GND")
		(6 "In2.Cu" signal "L3")
		(8 "In3.Cu" signal "L4VCC")
		(10 "In4.Cu" signal "L5VCC")
		(12 "In5.Cu" signal "L6")
		(14 "In6.Cu" signal "L7GND")
		(2 "B.Cu" signal "BOTTOM")
		(9 "F.Adhes" user "F.Adhesive")
		(11 "B.Adhes" user "B.Adhesive")
		(13 "F.Paste" user "Package Geometry/Pastemask Top")
		(15 "B.Paste" user "Package Geometry/Pastemask Bottom")
		(5 "F.SilkS" user "Ref Des/Silkscreen Top")
		(7 "B.SilkS" user "Ref Des/Silkscreen Bottom")
		(1 "F.Mask" user "Board Geometry/Soldermask Top")
		(3 "B.Mask" user "Board Geometry/Soldermask Bottom")
		(17 "Dwgs.User" user "User.Drawings")
		(19 "Cmts.User" user "User.Comments")
		(21 "Eco1.User" user "User.Eco1")
		(23 "Eco2.User" user "User.Eco2")
		(25 "Edge.Cuts" user "Board Geometry/Outline")
		(27 "Margin" user)
		(31 "F.CrtYd" user "Package Geometry/Place Bound Top")
		(29 "B.CrtYd" user "Package Geometry/Place Bound Bottom")
		(35 "F.Fab" user "Ref Des/Assembly Top")
		(33 "B.Fab" user "Ref Des/Assembly Bottom")
	)
	(footprint ""
		(layer "F.Cu")
		(at 326.39 -168.021)
		(property "Reference" "R289"
			(at 0 0 0)
			(layer "F.SilkS")
			(hide yes)
			(effects
				(font
					(size 1.27 1.27)
				)
			)
		)
		(property "Value" "10KR2F-2-GP"
			(at 0.064008 -3.993896 0)
			(unlocked yes)
			(layer "F.Fab")
			(hide yes)
			(effects
				(font
					(size 1.016 1.016)
					(thickness 0.1524)
				)
			)
		)
		(property "Device Type" "R402H16"
			(at 0.064008 -5.517896 0)
			(unlocked yes)
			(layer "F.Fab")
			(hide yes)
			(effects
				(font
					(size 1.016 1.016)
					(thickness 0.1524)
				)
			)
		)
		(duplicate_pad_numbers_are_jumpers no)
		(fp_line
			(start -0.508 -0.9398)
			(end -0.508 0.9398)
			(stroke
				(width 0.1524)
				(type default)
			)
			(layer "F.SilkS")
		)
		(fp_line
			(start 0.508 -0.9398)
			(end -0.508 -0.9398)
			(stroke
				(width 0.1524)
				(type default)
			)
			(layer "F.SilkS")
		)
		(fp_rect
			(start -0.508 0.9398)
			(end 0.508 -0.9398)
			(stroke
				(width 0)
				(type default)
			)
			(fill no)
			(layer "F.CrtYd")
		)
		(fp_rect
			(start -0.508 0.9398)
			(end 0.508 -0.9398)
			(stroke
				(width 0)
				(type default)
			)
			(fill no)
			(layer "F.Fab")
		)
		(pad "1" smd custom
			(at 0 -0.4445)
			(size 0.1397 0.1397)
			(layers "F.Cu" "F.Mask" "F.Paste")
			(net "P3V3_STBY")
			(options
				(clearance outline)
				(anchor circle)
			)
			(primitives
				(gr_poly
					(pts
						(arc
							(start -0.1778 -0.2794)
							(mid -0.249642 -0.249642)
							(end -0.2794 -0.1778)
						)
						(arc
							(start -0.2794 0.1778)
							(mid -0.249642 0.249642)
							(end -0.1778 0.2794)
						)
						(arc
							(start 0.1778 0.2794)
							(mid 0.249642 0.249642)
							(end 0.2794 0.1778)
						)
						(arc
							(start 0.2794 -0.1778)
							(mid 0.249642 -0.249642)
							(end 0.1778 -0.2794)
						)
					)
					(width 0)
					(fill yes)
				)
			)
		)
		(pad "2" smd custom
			(at 0 0.4445)
			(size 0.1397 0.1397)
			(layers "F.Cu" "F.Mask" "F.Paste")
			(net "BMC_UART_SWITCH_1R")
			(options
				(clearance outline)
				(anchor circle)
			)
			(primitives
				(gr_poly
					(pts
						(arc
							(start -0.1778 -0.2794)
							(mid -0.249642 -0.249642)
							(end -0.2794 -0.1778)
						)
						(arc
							(start -0.2794 0.1778)
							(mid -0.249642 0.249642)
							(end -0.1778 0.2794)
						)
						(arc
							(start 0.1778 0.2794)
							(mid 0.249642 0.249642)
							(end 0.2794 0.1778)
						)
						(arc
							(start 0.2794 -0.1778)
							(mid 0.249642 -0.249642)
							(end 0.1778 -0.2794)
						)
					)
					(width 0)
					(fill yes)
				)
			)
		)
	)
	(footprint ""
		(layer "F.Cu")
		(at 266.065 -177.038 90)
		(property "Reference" "R369"
			(at 0 0 90)
			(layer "F.SilkS")
			(hide yes)
			(effects
				(font
					(size 1.27 1.27)
				)
			)
		)
		(property "Value" "3K3R2F-2-GP"
			(at 0.064008 -3.993896 90)
			(unlocked yes)
			(layer "F.Fab")
			(hide yes)
			(effects
				(font
					(size 1.016 1.016)
					(thickness 0.1524)
				)
			)
		)
		(property "Device Type" "R402H16"
			(at 0.064008 -5.517896 90)
			(unlocked yes)
			(layer "F.Fab")
			(hide yes)
			(effects
				(font
					(size 1.016 1.016)
					(thickness 0.1524)
				)
			)
		)
		(duplicate_pad_numbers_are_jumpers no)
		(fp_line
			(start 0.508 -0.9398)
			(end -0.508 -0.9398)
			(stroke
				(width 0.1524)
				(type default)
			)
			(layer "F.SilkS")
		)
		(fp_line
			(start -0.508 -0.9398)
			(end -0.508 0.9398)
			(stroke
				(width 0.1524)
				(type default)
			)
			(layer "F.SilkS")
		)
		(fp_rect
			(start -0.508 0.9398)
			(end 0.508 -0.9398)
			(stroke
				(width 0)
				(type default)
			)
			(fill no)
			(layer "F.CrtYd")
		)
		(fp_rect
			(start -0.508 0.9398)
			(end 0.508 -0.9398)
			(stroke
				(width 0)
				(type default)
			)
			(fill no)
			(layer "F.Fab")
		)
		(pad "1" smd custom
			(at 0 -0.4445 90)
			(size 0.1397 0.1397)
			(layers "F.Cu" "F.Mask" "F.Paste")
			(net "P3V3_STBY")
			(options
				(clearance outline)
				(anchor circle)
			)
			(primitives
				(gr_poly
					(pts
						(arc
							(start -0.1778 -0.2794)
							(mid -0.249642 -0.249642)
							(end -0.2794 -0.1778)
						)
						(arc
							(start -0.2794 0.1778)
							(mid -0.249642 0.249642)
							(end -0.1778 0.2794)
						)
						(arc
							(start 0.1778 0.2794)
							(mid 0.249642 0.249642)
							(end 0.2794 0.1778)
						)
						(arc
							(start 0.2794 -0.1778)
							(mid 0.249642 -0.249642)
							(end 0.1778 -0.2794)
						)
					)
					(width 0)
					(fill yes)
				)
			)
		)
		(pad "2" smd custom
			(at 0 0.4445 90)
			(size 0.1397 0.1397)
			(layers "F.Cu" "F.Mask" "F.Paste")
			(net "ROMA23")
			(options
				(clearance outline)
				(anchor circle)
			)
			(primitives
				(gr_poly
					(pts
						(arc
							(start -0.1778 -0.2794)
							(mid -0.249642 -0.249642)
							(end -0.2794 -0.1778)
						)
						(arc
							(start -0.2794 0.1778)
							(mid -0.249642 0.249642)
							(end -0.1778 0.2794)
						)
						(arc
							(start 0.1778 0.2794)
							(mid 0.249642 0.249642)
							(end 0.2794 0.1778)
						)
						(arc
							(start 0.2794 -0.1778)
							(mid 0.249642 -0.249642)
							(end 0.1778 -0.2794)
						)
					)
					(width 0)
					(fill yes)
				)
			)
		)
	)
	(footprint ""
		(layer "F.Cu")
		(at 98.18497 -84.582)
		(property "Reference" "STP100"
			(at 0 0 0)
			(layer "F.SilkS")
			(hide yes)
			(effects
				(font
					(size 1.27 1.27)
				)
			)
		)
		(property "Value" "TPAD28"
			(at 0.0127 -1.8034 0)
			(unlocked yes)
			(layer "F.Fab")
			(hide yes)
			(effects
				(font
					(size 1.016 1.016)
					(thickness 0.1524)
				)
			)
		)
		(property "Device Type" "TPAD28"
			(at 0.0127 -3.3274 0)
			(unlocked yes)
			(layer "F.Fab")
			(hide yes)
			(effects
				(font
					(size 1.016 1.016)
					(thickness 0.1524)
				)
			)
		)
		(duplicate_pad_numbers_are_jumpers no)
		(fp_poly
			(pts
				(arc
					(start 0.3556 0)
					(mid -0.3556 0)
					(end 0.3556 0)
				)
			)
			(stroke
				(width 0)
				(type default)
			)
			(fill no)
			(layer "F.CrtYd")
		)
		(fp_poly
			(pts
				(arc
					(start 0.6096 0)
					(mid -0.6096 0)
					(end 0.6096 0)
				)
			)
			(stroke
				(width 0)
				(type default)
			)
			(fill no)
			(layer "F.Fab")
		)
		(pad "1" smd circle
			(at 0 0)
			(size 0.7112 0.7112)
			(layers "F.Cu" "F.Mask" "F.Paste")
			(net "LSI_T_N")
		)
	)
	(footprint ""
		(layer "F.Cu")
		(at 87.757 -223.139 -90)
		(property "Reference" "SR839"
			(at 0 0 270)
			(layer "F.SilkS")
			(hide yes)
			(effects
				(font
					(size 1.27 1.27)
				)
			)
		)
		(property "Value" "4K7R2F-GP"
			(at 0.064008 -3.993896 270)
			(unlocked yes)
			(layer "F.Fab")
			(hide yes)
			(effects
				(font
					(size 1.016 1.016)
					(thickness 0.1524)
				)
			)
		)
		(property "Device Type" "R402H16"
			(at 0.064008 -5.517896 270)
			(unlocked yes)
			(layer "F.Fab")
			(hide yes)
			(effects
				(font
					(size 1.016 1.016)
					(thickness 0.1524)
				)
			)
		)
		(duplicate_pad_numbers_are_jumpers no)
		(fp_line
			(start -0.508 -0.9398)
			(end -0.508 0.9398)
			(stroke
				(width 0.1524)
				(type default)
			)
			(layer "F.SilkS")
		)
		(fp_line
			(start 0.508 -0.9398)
			(end -0.508 -0.9398)
			(stroke
				(width 0.1524)
				(type default)
			)
			(layer "F.SilkS")
		)
		(fp_rect
			(start -0.508 0.9398)
			(end 0.508 -0.9398)
			(stroke
				(width 0)
				(type default)
			)
			(fill no)
			(layer "F.CrtYd")
		)
		(fp_rect
			(start -0.508 0.9398)
			(end 0.508 -0.9398)
			(stroke
				(width 0)
				(type default)
			)
			(fill no)
			(layer "F.Fab")
		)
		(pad "1" smd custom
			(at 0 -0.4445 270)
			(size 0.1397 0.1397)
			(layers "F.Cu" "F.Mask" "F.Paste")
			(net "EXP_SDA_L_0")
			(options
				(clearance outline)
				(anchor circle)
			)
			(primitives
				(gr_poly
					(pts
						(arc
							(start -0.1778 -0.2794)
							(mid -0.249642 -0.249642)
							(end -0.2794 -0.1778)
						)
						(arc
							(start -0.2794 0.1778)
							(mid -0.249642 0.249642)
							(end -0.1778 0.2794)
						)
						(arc
							(start 0.1778 0.2794)
							(mid 0.249642 0.249642)
							(end 0.2794 0.1778)
						)
						(arc
							(start 0.2794 -0.1778)
							(mid 0.249642 -0.249642)
							(end 0.1778 -0.2794)
						)
					)
					(width 0)
					(fill yes)
				)
			)
		)
		(pad "2" smd custom
			(at 0 0.4445 270)
			(size 0.1397 0.1397)
			(layers "F.Cu" "F.Mask" "F.Paste")
			(net "P3V3_STBY")
			(options
				(clearance outline)
				(anchor circle)
			)
			(primitives
				(gr_poly
					(pts
						(arc
							(start -0.1778 -0.2794)
							(mid -0.249642 -0.249642)
							(end -0.2794 -0.1778)
						)
						(arc
							(start -0.2794 0.1778)
							(mid -0.249642 0.249642)
							(end -0.1778 0.2794)
						)
						(arc
							(start 0.1778 0.2794)
							(mid 0.249642 0.249642)
							(end 0.2794 0.1778)
						)
						(arc
							(start 0.2794 -0.1778)
							(mid 0.249642 -0.249642)
							(end 0.1778 -0.2794)
						)
					)
					(width 0)
					(fill yes)
				)
			)
		)
	)
	(footprint ""
		(layer "F.Cu")
		(at 141.986 -38.862 180)
		(property "Reference" "SR692"
			(at 0 0 180)
			(layer "F.SilkS")
			(hide yes)
			(effects
				(font
					(size 1.27 1.27)
				)
			)
		)
		(property "Value" "10KR2F-2-GP"
			(at 0.064008 -3.993896 180)
			(unlocked yes)
			(layer "F.Fab")
			(hide yes)
			(effects
				(font
					(size 1.016 1.016)
					(thickness 0.1524)
				)
			)
		)
		(property "Device Type" "R402H16"
			(at 0.064008 -5.517896 180)
			(unlocked yes)
			(layer "F.Fab")
			(hide yes)
			(effects
				(font
					(size 1.016 1.016)
					(thickness 0.1524)
				)
			)
		)
		(duplicate_pad_numbers_are_jumpers no)
		(fp_line
			(start 0.508 -0.9398)
			(end -0.508 -0.9398)
			(stroke
				(width 0.1524)
				(type default)
			)
			(layer "F.SilkS")
		)
		(fp_line
			(start -0.508 -0.9398)
			(end -0.508 0.9398)
			(stroke
				(width 0.1524)
				(type default)
			)
			(layer "F.SilkS")
		)
		(fp_rect
			(start -0.508 0.9398)
			(end 0.508 -0.9398)
			(stroke
				(width 0)
				(type default)
			)
			(fill no)
			(layer "F.CrtYd")
		)
		(fp_rect
			(start -0.508 0.9398)
			(end 0.508 -0.9398)
			(stroke
				(width 0)
				(type default)
			)
			(fill no)
			(layer "F.Fab")
		)
		(pad "1" smd custom
			(at 0 -0.4445 180)
			(size 0.1397 0.1397)
			(layers "F.Cu" "F.Mask" "F.Paste")
			(net "P1V8_C")
			(options
				(clearance outline)
				(anchor circle)
			)
			(primitives
				(gr_poly
					(pts
						(arc
							(start -0.1778 -0.2794)
							(mid -0.249642 -0.249642)
							(end -0.2794 -0.1778)
						)
						(arc
							(start -0.2794 0.1778)
							(mid -0.249642 0.249642)
							(end -0.1778 0.2794)
						)
						(arc
							(start 0.1778 0.2794)
							(mid 0.249642 0.249642)
							(end 0.2794 0.1778)
						)
						(arc
							(start 0.2794 -0.1778)
							(mid 0.249642 -0.249642)
							(end 0.1778 -0.2794)
						)
					)
					(width 0)
					(fill yes)
				)
			)
		)
		(pad "2" smd custom
			(at 0 0.4445 180)
			(size 0.1397 0.1397)
			(layers "F.Cu" "F.Mask" "F.Paste")
			(net "XM_ADDR_22")
			(options
				(clearance outline)
				(anchor circle)
			)
			(primitives
				(gr_poly
					(pts
						(arc
							(start -0.1778 -0.2794)
							(mid -0.249642 -0.249642)
							(end -0.2794 -0.1778)
						)
						(arc
							(start -0.2794 0.1778)
							(mid -0.249642 0.249642)
							(end -0.1778 0.2794)
						)
						(arc
							(start 0.1778 0.2794)
							(mid 0.249642 0.249642)
							(end 0.2794 0.1778)
						)
						(arc
							(start 0.2794 -0.1778)
							(mid 0.249642 -0.249642)
							(end 0.1778 -0.2794)
						)
					)
					(width 0)
					(fill yes)
				)
			)
		)
	)
	(footprint ""
		(layer "F.Cu")
		(at 303.318672 -67.07124 -90)
		(property "Reference" "R270"
			(at 0 0 270)
			(layer "F.SilkS")
			(hide yes)
			(effects
				(font
					(size 1.27 1.27)
				)
			)
		)
		(property "Value" "0R2J-2-GP"
			(at 0.064008 -3.993896 270)
			(unlocked yes)
			(layer "F.Fab")
			(hide yes)
			(effects
				(font
					(size 1.016 1.016)
					(thickness 0.1524)
				)
			)
		)
		(property "Device Type" "R402H16"
			(at 0.064008 -5.517896 270)
			(unlocked yes)
			(layer "F.Fab")
			(hide yes)
			(effects
				(font
					(size 1.016 1.016)
					(thickness 0.1524)
				)
			)
		)
		(duplicate_pad_numbers_are_jumpers no)
		(fp_line
			(start -0.508 -0.9398)
			(end -0.508 0.9398)
			(stroke
				(width 0.1524)
				(type default)
			)
			(layer "F.SilkS")
		)
		(fp_line
			(start 0.508 -0.9398)
			(end -0.508 -0.9398)
			(stroke
				(width 0.1524)
				(type default)
			)
			(layer "F.SilkS")
		)
		(fp_rect
			(start -0.508 0.9398)
			(end 0.508 -0.9398)
			(stroke
				(width 0)
				(type default)
			)
			(fill no)
			(layer "F.CrtYd")
		)
		(fp_rect
			(start -0.508 0.9398)
			(end 0.508 -0.9398)
			(stroke
				(width 0)
				(type default)
			)
			(fill no)
			(layer "F.Fab")
		)
		(pad "1" smd custom
			(at 0 -0.4445 270)
			(size 0.1397 0.1397)
			(layers "F.Cu" "F.Mask" "F.Paste")
			(net "PCIE_10G_REFCLK_P")
			(options
				(clearance outline)
				(anchor circle)
			)
			(primitives
				(gr_poly
					(pts
						(arc
							(start -0.1778 -0.2794)
							(mid -0.249642 -0.249642)
							(end -0.2794 -0.1778)
						)
						(arc
							(start -0.2794 0.1778)
							(mid -0.249642 0.249642)
							(end -0.1778 0.2794)
						)
						(arc
							(start 0.1778 0.2794)
							(mid 0.249642 0.249642)
							(end 0.2794 0.1778)
						)
						(arc
							(start 0.2794 -0.1778)
							(mid 0.249642 -0.249642)
							(end 0.1778 -0.2794)
						)
					)
					(width 0)
					(fill yes)
				)
			)
		)
		(pad "2" smd custom
			(at 0 0.4445 270)
			(size 0.1397 0.1397)
			(layers "F.Cu" "F.Mask" "F.Paste")
			(net "CLK_100M_CLKBUFF_ENET1_DP")
			(options
				(clearance outline)
				(anchor circle)
			)
			(primitives
				(gr_poly
					(pts
						(arc
							(start -0.1778 -0.2794)
							(mid -0.249642 -0.249642)
							(end -0.2794 -0.1778)
						)
						(arc
							(start -0.2794 0.1778)
							(mid -0.249642 0.249642)
							(end -0.1778 0.2794)
						)
						(arc
							(start 0.1778 0.2794)
							(mid 0.249642 0.249642)
							(end 0.2794 0.1778)
						)
						(arc
							(start 0.2794 -0.1778)
							(mid 0.249642 -0.249642)
							(end 0.1778 -0.2794)
						)
					)
					(width 0)
					(fill yes)
				)
			)
		)
	)
	(footprint ""
		(layer "F.Cu")
		(at 38.354 -215.392 90)
		(property "Reference" "SC1286"
			(at 0 0 90)
			(layer "F.SilkS")
			(hide yes)
			(effects
				(font
					(size 1.27 1.27)
				)
			)
		)
		(property "Value" "SCD1U16V2KX-3GP"
			(at 1.1811 -2.7051 90)
			(unlocked yes)
			(layer "F.Fab")
			(hide yes)
			(effects
				(font
					(size 1.016 1.016)
					(thickness 0.1524)
				)
			)
		)
		(property "Device Type" "C402H22"
			(at 1.1811 -4.2291 90)
			(unlocked yes)
			(layer "F.Fab")
			(hide yes)
			(effects
				(font
					(size 1.016 1.016)
					(thickness 0.1524)
				)
			)
		)
		(duplicate_pad_numbers_are_jumpers no)
		(fp_rect
			(start -0.4318 0.9525)
			(end 0.4318 -0.9525)
			(stroke
				(width 0)
				(type default)
			)
			(fill no)
			(layer "F.CrtYd")
		)
		(fp_rect
			(start -0.4318 0.9525)
			(end 0.4318 -0.9525)
			(stroke
				(width 0)
				(type default)
			)
			(fill no)
			(layer "F.Fab")
		)
		(pad "1" smd custom
			(at 0 -0.4445 90)
			(size 0.1524 0.1524)
			(layers "F.Cu" "F.Mask" "F.Paste")
			(net "EXP_I2C_VREF_4")
			(options
				(clearance outline)
				(anchor circle)
			)
			(primitives
				(gr_poly
					(pts
						(arc
							(start 0.3048 -0.2032)
							(mid 0.275042 -0.275042)
							(end 0.2032 -0.3048)
						)
						(arc
							(start -0.2032 -0.3048)
							(mid -0.275042 -0.275042)
							(end -0.3048 -0.2032)
						)
						(arc
							(start -0.3048 0.2032)
							(mid -0.275042 0.275042)
							(end -0.2032 0.3048)
						)
						(arc
							(start 0.2032 0.3048)
							(mid 0.275042 0.275042)
							(end 0.3048 0.2032)
						)
					)
					(width 0)
					(fill yes)
				)
			)
		)
		(pad "2" smd custom
			(at 0 0.4445 90)
			(size 0.1524 0.1524)
			(layers "F.Cu" "F.Mask" "F.Paste")
			(net "GND")
			(options
				(clearance outline)
				(anchor circle)
			)
			(primitives
				(gr_poly
					(pts
						(arc
							(start 0.3048 -0.2032)
							(mid 0.275042 -0.275042)
							(end 0.2032 -0.3048)
						)
						(arc
							(start -0.2032 -0.3048)
							(mid -0.275042 -0.275042)
							(end -0.3048 -0.2032)
						)
						(arc
							(start -0.3048 0.2032)
							(mid -0.275042 0.275042)
							(end -0.2032 0.3048)
						)
						(arc
							(start 0.2032 0.3048)
							(mid 0.275042 0.275042)
							(end 0.3048 0.2032)
						)
					)
					(width 0)
					(fill yes)
				)
			)
		)
	)
	(footprint ""
		(layer "F.Cu")
		(at 306.578 -183.007)
		(property "Reference" "TP174"
			(at 0 0 0)
			(layer "F.SilkS")
			(hide yes)
			(effects
				(font
					(size 1.27 1.27)
				)
			)
		)
		(property "Value" "TPAD28"
			(at 0.0127 -1.8034 0)
			(unlocked yes)
			(layer "F.Fab")
			(hide yes)
			(effects
				(font
					(size 1.016 1.016)
					(thickness 0.1524)
				)
			)
		)
		(property "Device Type" "TPAD28"
			(at 0.0127 -3.3274 0)
			(unlocked yes)
			(layer "F.Fab")
			(hide yes)
			(effects
				(font
					(size 1.016 1.016)
					(thickness 0.1524)
				)
			)
		)
		(duplicate_pad_numbers_are_jumpers no)
		(fp_poly
			(pts
				(arc
					(start 0.3556 0)
					(mid -0.3556 0)
					(end 0.3556 0)
				)
			)
			(stroke
				(width 0)
				(type default)
			)
			(fill no)
			(layer "F.CrtYd")
		)
		(fp_poly
			(pts
				(arc
					(start 0.6096 0)
					(mid -0.6096 0)
					(end 0.6096 0)
				)
			)
			(stroke
				(width 0)
				(type default)
			)
			(fill no)
			(layer "F.Fab")
		)
		(pad "1" smd circle
			(at 0 0)
			(size 0.7112 0.7112)
			(layers "F.Cu" "F.Mask" "F.Paste")
			(net "TP_BMC_GPIOM2")
		)
	)
)
